(kicad_pcb
	(version 20260206)
	(generator "pcbnew")
	(generator_version "10.0")
	(general
		(thickness 1.6)
		(legacy_teardrops no)
	)
	(paper "A4")
	(title_block
		(title "04192023_DAF0TMB3IC0_F0TG_MB_C_brd_V02_OCP.brd")
		(comment 1 "Grand Teton / footprint 3955 of 8354 (U25), pads 2559-2668 of 6102")
	)
	(layers
		(0 "F.Cu" signal "TOP")
		(4 "In1.Cu" signal "GND")
		(6 "In2.Cu" signal "IN1")
		(8 "In3.Cu" signal "GND1")
		(10 "In4.Cu" signal "IN2")
		(12 "In5.Cu" signal "GND2")
		(14 "In6.Cu" signal "IN3")
		(16 "In7.Cu" signal "GND3")
		(18 "In8.Cu" signal "VCC")
		(20 "In9.Cu" signal "VCC1")
		(22 "In10.Cu" signal "GND4")
		(24 "In11.Cu" signal "IN4")
		(26 "In12.Cu" signal "GND5")
		(28 "In13.Cu" signal "IN5")
		(30 "In14.Cu" signal "GND6")
		(32 "In15.Cu" signal "IN6")
		(34 "In16.Cu" signal "GND7")
		(2 "B.Cu" signal "BOTTOM")
		(9 "F.Adhes" user "F.Adhesive")
		(11 "B.Adhes" user "B.Adhesive")
		(13 "F.Paste" user "Package Geometry/Pastemask Top")
		(15 "B.Paste" user "Package Geometry/Pastemask Bottom")
		(5 "F.SilkS" user "Ref Des/Silkscreen Top")
		(7 "B.SilkS" user "Ref Des/Silkscreen Bottom")
		(1 "F.Mask" user "Board Geometry/Soldermask Top")
		(3 "B.Mask" user "Board Geometry/Soldermask Bottom")
		(17 "Dwgs.User" user "User.Drawings")
		(19 "Cmts.User" user "User.Comments")
		(21 "Eco1.User" user "User.Eco1")
		(23 "Eco2.User" user "User.Eco2")
		(25 "Edge.Cuts" user "Board Geometry/Outline")
		(27 "Margin" user)
		(31 "F.CrtYd" user "Package Geometry/Place Bound Top")
		(29 "B.CrtYd" user "Package Geometry/Place Bound Bottom")
		(35 "F.Fab" user "Ref Des/Assembly Top")
		(33 "B.Fab" user "Ref Des/Assembly Bottom")
	)
	(footprint ""
		(layer "F.Cu")
		(at 359.867962 -258.880102 180)
		(property "Reference" "U25"
			(at -45.78477 -62.086744 0)
			(unlocked yes)
			(layer "F.SilkS")
			(effects
				(font
					(size 0.7874 0.5842)
					(thickness 0.1524)
				)
			)
		)
		(property "Value" ""
			(at 0 0 180)
			(layer "F.Fab")
			(effects
				(font
					(size 1.27 1.27)
				)
			)
		)
		(duplicate_pad_numbers_are_jumpers no)
		(pad "BV41" smd circle
			(at 2.670048 11.700002 180)
			(size 0.450088 0.450088)
			(layers "F.Cu" "F.Mask" "F.Paste")
			(net "P5E_CPU0_P0_RX_DN<14>")
		)
		(pad "BV42" smd circle
			(at 3.610102 11.700002 180)
			(size 0.450088 0.450088)
			(layers "F.Cu" "F.Mask" "F.Paste")
			(net "GND")
		)
		(pad "BV43" smd circle
			(at 4.549902 11.700002 180)
			(size 0.450088 0.450088)
			(layers "F.Cu" "F.Mask" "F.Paste")
			(net "GND")
		)
		(pad "BV44" smd circle
			(at 5.489956 11.700002 180)
			(size 0.450088 0.450088)
			(layers "F.Cu" "F.Mask" "F.Paste")
			(net "GND")
		)
		(pad "BV45" smd circle
			(at 6.43001 11.700002 180)
			(size 0.450088 0.450088)
			(layers "F.Cu" "F.Mask" "F.Paste")
			(net "GND")
		)
		(pad "BV46" smd circle
			(at 7.370064 11.700002 180)
			(size 0.450088 0.450088)
			(layers "F.Cu" "F.Mask" "F.Paste")
			(net "GND")
		)
		(pad "BV47" smd circle
			(at 8.310118 11.700002 180)
			(size 0.450088 0.450088)
			(layers "F.Cu" "F.Mask" "F.Paste")
			(net "GND")
		)
		(pad "BV48" smd circle
			(at 9.249918 11.700002 180)
			(size 0.450088 0.450088)
			(layers "F.Cu" "F.Mask" "F.Paste")
			(net "GND")
		)
		(pad "BV49" smd circle
			(at 10.189972 11.700002 180)
			(size 0.450088 0.450088)
			(layers "F.Cu" "F.Mask" "F.Paste")
			(net "GND")
		)
		(pad "BV50" smd circle
			(at 11.130026 11.700002 180)
			(size 0.450088 0.450088)
			(layers "F.Cu" "F.Mask" "F.Paste")
			(net "GND")
		)
		(pad "BV51" smd circle
			(at 12.07008 11.700002 180)
			(size 0.450088 0.450088)
			(layers "F.Cu" "F.Mask" "F.Paste")
			(net "GND")
		)
		(pad "BV52" smd circle
			(at 13.00988 11.700002 180)
			(size 0.450088 0.450088)
			(layers "F.Cu" "F.Mask" "F.Paste")
			(net "GND")
		)
		(pad "BV53" smd circle
			(at 13.949934 11.700002 180)
			(size 0.450088 0.450088)
			(layers "F.Cu" "F.Mask" "F.Paste")
			(net "GND")
		)
		(pad "BV54" smd circle
			(at 14.889988 11.700002 180)
			(size 0.450088 0.450088)
			(layers "F.Cu" "F.Mask" "F.Paste")
			(net "PVDDIO_P0")
		)
		(pad "BV55" smd circle
			(at 15.830042 11.700002 180)
			(size 0.450088 0.450088)
			(layers "F.Cu" "F.Mask" "F.Paste")
			(net "M_C_CPU0_SB_CB<7>")
		)
		(pad "BV56" smd circle
			(at 16.770096 11.700002 180)
			(size 0.450088 0.450088)
			(layers "F.Cu" "F.Mask" "F.Paste")
			(net "M_C_CPU0_SB_DQS_DP<9>")
		)
		(pad "BV57" smd circle
			(at 17.709896 11.700002 180)
			(size 0.450088 0.450088)
			(layers "F.Cu" "F.Mask" "F.Paste")
			(net "PVDDIO_P0")
		)
		(pad "BV58" smd circle
			(at 18.64995 11.700002 180)
			(size 0.450088 0.450088)
			(layers "F.Cu" "F.Mask" "F.Paste")
			(net "M_D_CPU0_SB_CB<7>")
		)
		(pad "BV59" smd circle
			(at 19.590004 11.700002 180)
			(size 0.450088 0.450088)
			(layers "F.Cu" "F.Mask" "F.Paste")
			(net "GND")
		)
		(pad "BV60" smd circle
			(at 20.530058 11.700002 180)
			(size 0.450088 0.450088)
			(layers "F.Cu" "F.Mask" "F.Paste")
			(net "M_D_CPU0_SB_DQS_DP<9>")
		)
		(pad "BV61" smd circle
			(at 21.470112 11.700002 180)
			(size 0.450088 0.450088)
			(layers "F.Cu" "F.Mask" "F.Paste")
			(net "GND")
		)
		(pad "BV62" smd circle
			(at 22.409912 11.700002 180)
			(size 0.450088 0.450088)
			(layers "F.Cu" "F.Mask" "F.Paste")
			(net "M_B_CPU0_SB_CB<7>")
		)
		(pad "BV63" smd circle
			(at 23.349966 11.700002 180)
			(size 0.450088 0.450088)
			(layers "F.Cu" "F.Mask" "F.Paste")
			(net "M_B_CPU0_SB_DQS_DP<9>")
		)
		(pad "BV64" smd circle
			(at 24.29002 11.700002 180)
			(size 0.450088 0.450088)
			(layers "F.Cu" "F.Mask" "F.Paste")
			(net "PVDDIO_P0")
		)
		(pad "BV65" smd circle
			(at 25.230074 11.700002 180)
			(size 0.450088 0.450088)
			(layers "F.Cu" "F.Mask" "F.Paste")
			(net "M_F_CPU0_SB_CB<7>")
		)
		(pad "BV66" smd circle
			(at 26.170128 11.700002 180)
			(size 0.450088 0.450088)
			(layers "F.Cu" "F.Mask" "F.Paste")
			(net "GND")
		)
		(pad "BV67" smd circle
			(at 27.109928 11.700002 180)
			(size 0.450088 0.450088)
			(layers "F.Cu" "F.Mask" "F.Paste")
			(net "M_F_CPU0_SB_DQS_DP<9>")
		)
		(pad "BV68" smd circle
			(at 28.049982 11.700002 180)
			(size 0.450088 0.450088)
			(layers "F.Cu" "F.Mask" "F.Paste")
			(net "GND")
		)
		(pad "BV69" smd circle
			(at 28.990036 11.700002 180)
			(size 0.450088 0.450088)
			(layers "F.Cu" "F.Mask" "F.Paste")
			(net "M_E_CPU0_SB_CB<7>")
		)
		(pad "BV70" smd circle
			(at 29.93009 11.700002 180)
			(size 0.450088 0.450088)
			(layers "F.Cu" "F.Mask" "F.Paste")
			(net "M_E_CPU0_SB_DQS_DP<9>")
		)
		(pad "BV71" smd circle
			(at 30.86989 11.700002 180)
			(size 0.450088 0.450088)
			(layers "F.Cu" "F.Mask" "F.Paste")
			(net "PVDDIO_P0")
		)
		(pad "BV72" smd circle
			(at 31.809944 11.700002 180)
			(size 0.450088 0.450088)
			(layers "F.Cu" "F.Mask" "F.Paste")
			(net "M_A_CPU0_SB_CB<7>")
		)
		(pad "BV73" smd circle
			(at 32.749998 11.700002 180)
			(size 0.450088 0.450088)
			(layers "F.Cu" "F.Mask" "F.Paste")
			(net "GND")
		)
		(pad "BV74" smd circle
			(at 33.690052 11.700002 180)
			(size 0.450088 0.450088)
			(layers "F.Cu" "F.Mask" "F.Paste")
			(net "M_A_CPU0_SB_DQS_DP<9>")
		)
		(pad "BW1" smd circle
			(at -34.459926 12.510008 180)
			(size 0.450088 0.450088)
			(layers "F.Cu" "F.Mask" "F.Paste")
			(net "GND")
		)
		(pad "BW2" smd circle
			(at -33.519872 12.510008 180)
			(size 0.450088 0.450088)
			(layers "F.Cu" "F.Mask" "F.Paste")
			(net "M_G_CPU0_SB_DQS_DN<9>")
		)
		(pad "BW3" smd circle
			(at -32.580072 12.510008 180)
			(size 0.450088 0.450088)
			(layers "F.Cu" "F.Mask" "F.Paste")
			(net "M_G_CPU0_SB_DQS_DN<4>")
		)
		(pad "BW4" smd circle
			(at -31.640018 12.510008 180)
			(size 0.450088 0.450088)
			(layers "F.Cu" "F.Mask" "F.Paste")
			(net "GND")
		)
		(pad "BW5" smd circle
			(at -30.699964 12.510008 180)
			(size 0.450088 0.450088)
			(layers "F.Cu" "F.Mask" "F.Paste")
			(net "M_K_CPU0_SB_DQS_DN<9>")
		)
		(pad "BW6" smd circle
			(at -29.75991 12.510008 180)
			(size 0.450088 0.450088)
			(layers "F.Cu" "F.Mask" "F.Paste")
			(net "GND")
		)
		(pad "BW7" smd circle
			(at -28.82011 12.510008 180)
			(size 0.450088 0.450088)
			(layers "F.Cu" "F.Mask" "F.Paste")
			(net "M_K_CPU0_SB_DQS_DN<4>")
		)
		(pad "BW8" smd circle
			(at -27.880056 12.510008 180)
			(size 0.450088 0.450088)
			(layers "F.Cu" "F.Mask" "F.Paste")
			(net "GND")
		)
		(pad "BW9" smd circle
			(at -26.940002 12.510008 180)
			(size 0.450088 0.450088)
			(layers "F.Cu" "F.Mask" "F.Paste")
			(net "M_L_CPU0_SB_DQS_DN<9>")
		)
		(pad "BW10" smd circle
			(at -25.999948 12.510008 180)
			(size 0.450088 0.450088)
			(layers "F.Cu" "F.Mask" "F.Paste")
			(net "M_L_CPU0_SB_DQS_DN<4>")
		)
		(pad "BW11" smd circle
			(at -25.059894 12.510008 180)
			(size 0.450088 0.450088)
			(layers "F.Cu" "F.Mask" "F.Paste")
			(net "GND")
		)
		(pad "BW12" smd circle
			(at -24.120094 12.510008 180)
			(size 0.450088 0.450088)
			(layers "F.Cu" "F.Mask" "F.Paste")
			(net "M_H_CPU0_SB_DQS_DN<9>")
		)
		(pad "BW13" smd circle
			(at -23.18004 12.510008 180)
			(size 0.450088 0.450088)
			(layers "F.Cu" "F.Mask" "F.Paste")
			(net "GND")
		)
		(pad "BW14" smd circle
			(at -22.239986 12.510008 180)
			(size 0.450088 0.450088)
			(layers "F.Cu" "F.Mask" "F.Paste")
			(net "M_H_CPU0_SB_DQS_DN<4>")
		)
		(pad "BW15" smd circle
			(at -21.299932 12.510008 180)
			(size 0.450088 0.450088)
			(layers "F.Cu" "F.Mask" "F.Paste")
			(net "GND")
		)
		(pad "BW16" smd circle
			(at -20.359878 12.510008 180)
			(size 0.450088 0.450088)
			(layers "F.Cu" "F.Mask" "F.Paste")
			(net "M_J_CPU0_SB_DQS_DN<9>")
		)
		(pad "BW17" smd circle
			(at -19.420078 12.510008 180)
			(size 0.450088 0.450088)
			(layers "F.Cu" "F.Mask" "F.Paste")
			(net "M_J_CPU0_SB_DQS_DN<4>")
		)
		(pad "BW18" smd circle
			(at -18.480024 12.510008 180)
			(size 0.450088 0.450088)
			(layers "F.Cu" "F.Mask" "F.Paste")
			(net "GND")
		)
		(pad "BW19" smd circle
			(at -17.53997 12.510008 180)
			(size 0.450088 0.450088)
			(layers "F.Cu" "F.Mask" "F.Paste")
			(net "M_I_CPU0_SB_DQS_DN<9>")
		)
		(pad "BW20" smd circle
			(at -16.599916 12.510008 180)
			(size 0.450088 0.450088)
			(layers "F.Cu" "F.Mask" "F.Paste")
			(net "GND")
		)
		(pad "BW21" smd circle
			(at -15.660116 12.510008 180)
			(size 0.450088 0.450088)
			(layers "F.Cu" "F.Mask" "F.Paste")
			(net "M_I_CPU0_SB_DQS_DN<4>")
		)
		(pad "BW22" smd circle
			(at -14.720062 12.510008 180)
			(size 0.450088 0.450088)
			(layers "F.Cu" "F.Mask" "F.Paste")
			(net "GND")
		)
		(pad "BW23" smd circle
			(at -13.780008 12.510008 180)
			(size 0.450088 0.450088)
			(layers "F.Cu" "F.Mask" "F.Paste")
			(net "P5E_CPU0_P2_TX_DN<15>")
		)
		(pad "BW24" smd circle
			(at -12.839954 12.510008 180)
			(size 0.450088 0.450088)
			(layers "F.Cu" "F.Mask" "F.Paste")
			(net "P5E_CPU0_P2_TX_DP<15>")
		)
		(pad "BW25" smd circle
			(at -11.8999 12.510008 180)
			(size 0.450088 0.450088)
			(layers "F.Cu" "F.Mask" "F.Paste")
			(net "GND")
		)
		(pad "BW26" smd circle
			(at -10.9601 12.510008 180)
			(size 0.450088 0.450088)
			(layers "F.Cu" "F.Mask" "F.Paste")
			(net "P5E_CPU0_P2_TX_DN<12>")
		)
		(pad "BW27" smd circle
			(at -10.020046 12.510008 180)
			(size 0.450088 0.450088)
			(layers "F.Cu" "F.Mask" "F.Paste")
			(net "P5E_CPU0_P2_TX_DP<12>")
		)
		(pad "BW28" smd circle
			(at -9.079992 12.510008 180)
			(size 0.450088 0.450088)
			(layers "F.Cu" "F.Mask" "F.Paste")
			(net "GND")
		)
		(pad "BW29" smd circle
			(at -8.139938 12.510008 180)
			(size 0.450088 0.450088)
			(layers "F.Cu" "F.Mask" "F.Paste")
			(net "P5E_CPU0_P2_TX_DN<9>")
		)
		(pad "BW30" smd circle
			(at -7.199884 12.510008 180)
			(size 0.450088 0.450088)
			(layers "F.Cu" "F.Mask" "F.Paste")
			(net "P5E_CPU0_P2_TX_DP<9>")
		)
		(pad "BW31" smd circle
			(at -6.260084 12.510008 180)
			(size 0.450088 0.450088)
			(layers "F.Cu" "F.Mask" "F.Paste")
			(net "GND")
		)
		(pad "BW32" smd circle
			(at -5.32003 12.510008 180)
			(size 0.450088 0.450088)
			(layers "F.Cu" "F.Mask" "F.Paste")
			(net "P5E_CPU0_P2_TX_DN<6>")
		)
		(pad "BW33" smd circle
			(at -4.379976 12.510008 180)
			(size 0.450088 0.450088)
			(layers "F.Cu" "F.Mask" "F.Paste")
			(net "P5E_CPU0_P2_TX_DP<6>")
		)
		(pad "BW34" smd circle
			(at -3.439922 12.510008 180)
			(size 0.450088 0.450088)
			(layers "F.Cu" "F.Mask" "F.Paste")
			(net "GND")
		)
		(pad "BW35" smd circle
			(at -2.500122 12.510008 180)
			(size 0.450088 0.450088)
			(layers "F.Cu" "F.Mask" "F.Paste")
			(net "PVDDCR_CPU1_P0")
		)
		(pad "BW36" smd circle
			(at -1.560068 12.510008 180)
			(size 0.450088 0.450088)
			(layers "F.Cu" "F.Mask" "F.Paste")
			(net "PVDDCR_CPU1_P0")
		)
		(pad "BW40" smd circle
			(at 1.260094 12.510008 180)
			(size 0.450088 0.450088)
			(layers "F.Cu" "F.Mask" "F.Paste")
			(net "PVDDCR_CPU1_P0")
		)
		(pad "BW41" smd circle
			(at 2.199894 12.510008 180)
			(size 0.450088 0.450088)
			(layers "F.Cu" "F.Mask" "F.Paste")
			(net "PVDDCR_CPU1_P0")
		)
		(pad "BW42" smd circle
			(at 3.139948 12.510008 180)
			(size 0.450088 0.450088)
			(layers "F.Cu" "F.Mask" "F.Paste")
			(net "GND")
		)
		(pad "BW43" smd circle
			(at 4.080002 12.510008 180)
			(size 0.450088 0.450088)
			(layers "F.Cu" "F.Mask" "F.Paste")
			(net "P5E_CPU0_P0_RX_DP<9>")
		)
		(pad "BW44" smd circle
			(at 5.020056 12.510008 180)
			(size 0.450088 0.450088)
			(layers "F.Cu" "F.Mask" "F.Paste")
			(net "P5E_CPU0_P0_RX_DN<9>")
		)
		(pad "BW45" smd circle
			(at 5.96011 12.510008 180)
			(size 0.450088 0.450088)
			(layers "F.Cu" "F.Mask" "F.Paste")
			(net "GND")
		)
		(pad "BW46" smd circle
			(at 6.89991 12.510008 180)
			(size 0.450088 0.450088)
			(layers "F.Cu" "F.Mask" "F.Paste")
			(net "P5E_CPU0_P0_RX_DP<6>")
		)
		(pad "BW47" smd circle
			(at 7.839964 12.510008 180)
			(size 0.450088 0.450088)
			(layers "F.Cu" "F.Mask" "F.Paste")
			(net "P5E_CPU0_P0_RX_DN<6>")
		)
		(pad "BW48" smd circle
			(at 8.780018 12.510008 180)
			(size 0.450088 0.450088)
			(layers "F.Cu" "F.Mask" "F.Paste")
			(net "GND")
		)
		(pad "BW49" smd circle
			(at 9.720072 12.510008 180)
			(size 0.450088 0.450088)
			(layers "F.Cu" "F.Mask" "F.Paste")
			(net "P5E_CPU0_P0_RX_DP<3>")
		)
		(pad "BW50" smd circle
			(at 10.659872 12.510008 180)
			(size 0.450088 0.450088)
			(layers "F.Cu" "F.Mask" "F.Paste")
			(net "P5E_CPU0_P0_RX_DN<3>")
		)
		(pad "BW51" smd circle
			(at 11.599926 12.510008 180)
			(size 0.450088 0.450088)
			(layers "F.Cu" "F.Mask" "F.Paste")
			(net "GND")
		)
		(pad "BW52" smd circle
			(at 12.53998 12.510008 180)
			(size 0.450088 0.450088)
			(layers "F.Cu" "F.Mask" "F.Paste")
			(net "P5E_CPU0_P0_RX_DP<0>")
		)
		(pad "BW53" smd circle
			(at 13.480034 12.510008 180)
			(size 0.450088 0.450088)
			(layers "F.Cu" "F.Mask" "F.Paste")
			(net "P5E_CPU0_P0_RX_DN<0>")
		)
		(pad "BW54" smd circle
			(at 14.420088 12.510008 180)
			(size 0.450088 0.450088)
			(layers "F.Cu" "F.Mask" "F.Paste")
			(net "GND")
		)
		(pad "BW55" smd circle
			(at 15.359888 12.510008 180)
			(size 0.450088 0.450088)
			(layers "F.Cu" "F.Mask" "F.Paste")
			(net "M_C_CPU0_SB_DQS_DN<4>")
		)
		(pad "BW56" smd circle
			(at 16.299942 12.510008 180)
			(size 0.450088 0.450088)
			(layers "F.Cu" "F.Mask" "F.Paste")
			(net "GND")
		)
		(pad "BW57" smd circle
			(at 17.239996 12.510008 180)
			(size 0.450088 0.450088)
			(layers "F.Cu" "F.Mask" "F.Paste")
			(net "M_C_CPU0_SB_DQS_DN<9>")
		)
		(pad "BW58" smd circle
			(at 18.18005 12.510008 180)
			(size 0.450088 0.450088)
			(layers "F.Cu" "F.Mask" "F.Paste")
			(net "GND")
		)
		(pad "BW59" smd circle
			(at 19.120104 12.510008 180)
			(size 0.450088 0.450088)
			(layers "F.Cu" "F.Mask" "F.Paste")
			(net "M_D_CPU0_SB_DQS_DN<4>")
		)
		(pad "BW60" smd circle
			(at 20.059904 12.510008 180)
			(size 0.450088 0.450088)
			(layers "F.Cu" "F.Mask" "F.Paste")
			(net "M_D_CPU0_SB_DQS_DN<9>")
		)
		(pad "BW61" smd circle
			(at 20.999958 12.510008 180)
			(size 0.450088 0.450088)
			(layers "F.Cu" "F.Mask" "F.Paste")
			(net "GND")
		)
		(pad "BW62" smd circle
			(at 21.940012 12.510008 180)
			(size 0.450088 0.450088)
			(layers "F.Cu" "F.Mask" "F.Paste")
			(net "M_B_CPU0_SB_DQS_DN<4>")
		)
		(pad "BW63" smd circle
			(at 22.880066 12.510008 180)
			(size 0.450088 0.450088)
			(layers "F.Cu" "F.Mask" "F.Paste")
			(net "GND")
		)
		(pad "BW64" smd circle
			(at 23.82012 12.510008 180)
			(size 0.450088 0.450088)
			(layers "F.Cu" "F.Mask" "F.Paste")
			(net "M_B_CPU0_SB_DQS_DN<9>")
		)
		(pad "BW65" smd circle
			(at 24.75992 12.510008 180)
			(size 0.450088 0.450088)
			(layers "F.Cu" "F.Mask" "F.Paste")
			(net "GND")
		)
		(pad "BW66" smd circle
			(at 25.699974 12.510008 180)
			(size 0.450088 0.450088)
			(layers "F.Cu" "F.Mask" "F.Paste")
			(net "M_F_CPU0_SB_DQS_DN<4>")
		)
		(pad "BW67" smd circle
			(at 26.640028 12.510008 180)
			(size 0.450088 0.450088)
			(layers "F.Cu" "F.Mask" "F.Paste")
			(net "M_F_CPU0_SB_DQS_DN<9>")
		)
		(pad "BW68" smd circle
			(at 27.580082 12.510008 180)
			(size 0.450088 0.450088)
			(layers "F.Cu" "F.Mask" "F.Paste")
			(net "GND")
		)
		(pad "BW69" smd circle
			(at 28.519882 12.510008 180)
			(size 0.450088 0.450088)
			(layers "F.Cu" "F.Mask" "F.Paste")
			(net "M_E_CPU0_SB_DQS_DN<4>")
		)
		(pad "BW70" smd circle
			(at 29.459936 12.510008 180)
			(size 0.450088 0.450088)
			(layers "F.Cu" "F.Mask" "F.Paste")
			(net "GND")
		)
		(pad "BW71" smd circle
			(at 30.39999 12.510008 180)
			(size 0.450088 0.450088)
			(layers "F.Cu" "F.Mask" "F.Paste")
			(net "M_E_CPU0_SB_DQS_DN<9>")
		)
		(pad "BW72" smd circle
			(at 31.340044 12.510008 180)
			(size 0.450088 0.450088)
			(layers "F.Cu" "F.Mask" "F.Paste")
			(net "GND")
		)
		(pad "BW73" smd circle
			(at 32.280098 12.510008 180)
			(size 0.450088 0.450088)
			(layers "F.Cu" "F.Mask" "F.Paste")
			(net "M_A_CPU0_SB_DQS_DN<4>")
		)
		(pad "BW74" smd circle
			(at 33.219898 12.510008 180)
			(size 0.450088 0.450088)
			(layers "F.Cu" "F.Mask" "F.Paste")
			(net "M_A_CPU0_SB_DQS_DN<9>")
		)
		(pad "BW75" smd circle
			(at 34.159952 12.510008 180)
			(size 0.450088 0.450088)
			(layers "F.Cu" "F.Mask" "F.Paste")
			(net "GND")
		)
		(pad "BY2" smd circle
			(at -33.990026 13.320014 180)
			(size 0.450088 0.450088)
			(layers "F.Cu" "F.Mask" "F.Paste")
			(net "M_G_CPU0_SB_CB<0>")
		)
		(pad "BY3" smd circle
			(at -33.049972 13.320014 180)
			(size 0.450088 0.450088)
			(layers "F.Cu" "F.Mask" "F.Paste")
			(net "GND")
		)
		(pad "BY4" smd circle
			(at -32.109918 13.320014 180)
			(size 0.450088 0.450088)
			(layers "F.Cu" "F.Mask" "F.Paste")
			(net "M_G_CPU0_SB_DQS_DP<4>")
		)
		(pad "BY5" smd circle
			(at -31.170118 13.320014 180)
			(size 0.450088 0.450088)
			(layers "F.Cu" "F.Mask" "F.Paste")
			(net "GND")
		)
	)
)
